# T6G (Grand Teton) — schematic netlist excerpt (pin names and nets, part order shuffled) for the footprints in the layout excerpt that follows; sources: Cadence DE-HDL packaged netlist, KiCad conversion of 04192023_DAF0TMB3IC0_F0TG_MB_C_brd_V02_OCP.brd

C2103  Q_CAP  22UF 4V 20% X6S  pkg C0402  page 74 : A = PVDDIO_P1 ; B = GND
C2580  Q_CAP  22UF 4V 20% X6S  pkg C0402  page 70 : A = PVDDCR_SOC_P0 ; B = GND

(kicad_pcb
	(version 20260206)
	(generator "pcbnew")
	(generator_version "10.0")
	(general
		(thickness 1.6)
		(legacy_teardrops no)
	)
	(paper "A4")
	(title_block
		(title "04192023_DAF0TMB3IC0_F0TG_MB_C_brd_V02_OCP.brd")
		(comment 1 "Grand Teton / footprints 7265-7266 of 8354")
	)
	(layers
		(0 "F.Cu" signal "TOP")
		(4 "In1.Cu" signal "GND")
		(6 "In2.Cu" signal "IN1")
		(8 "In3.Cu" signal "GND1")
		(10 "In4.Cu" signal "IN2")
		(12 "In5.Cu" signal "GND2")
		(14 "In6.Cu" signal "IN3")
		(16 "In7.Cu" signal "GND3")
		(18 "In8.Cu" signal "VCC")
		(20 "In9.Cu" signal "VCC1")
		(22 "In10.Cu" signal "GND4")
		(24 "In11.Cu" signal "IN4")
		(26 "In12.Cu" signal "GND5")
		(28 "In13.Cu" signal "IN5")
		(30 "In14.Cu" signal "GND6")
		(32 "In15.Cu" signal "IN6")
		(34 "In16.Cu" signal "GND7")
		(2 "B.Cu" signal "BOTTOM")
		(9 "F.Adhes" user "F.Adhesive")
		(11 "B.Adhes" user "B.Adhesive")
		(13 "F.Paste" user "Package Geometry/Pastemask Top")
		(15 "B.Paste" user "Package Geometry/Pastemask Bottom")
		(5 "F.SilkS" user "Ref Des/Silkscreen Top")
		(7 "B.SilkS" user "Ref Des/Silkscreen Bottom")
		(1 "F.Mask" user "Board Geometry/Soldermask Top")
		(3 "B.Mask" user "Board Geometry/Soldermask Bottom")
		(17 "Dwgs.User" user "User.Drawings")
		(19 "Cmts.User" user "User.Comments")
		(21 "Eco1.User" user "User.Eco1")
		(23 "Eco2.User" user "User.Eco2")
		(25 "Edge.Cuts" user "Board Geometry/Outline")
		(27 "Margin" user)
		(31 "F.CrtYd" user "Package Geometry/Place Bound Top")
		(29 "B.CrtYd" user "Package Geometry/Place Bound Bottom")
		(35 "F.Fab" user "Ref Des/Assembly Top")
		(33 "B.Fab" user "Ref Des/Assembly Bottom")
	)
	(footprint ""
		(layer "B.Cu")
		(at 100.478844 -259.73024 180)
		(property "Reference" "C2103"
			(at 0 0 0)
			(layer "B.SilkS")
			(hide yes)
			(effects
				(font
					(size 1.27 1.27)
				)
				(justify mirror)
			)
		)
		(property "Value" ""
			(at 0 0 0)
			(layer "B.Fab")
			(effects
				(font
					(size 1.27 1.27)
				)
				(justify mirror)
			)
		)
		(duplicate_pad_numbers_are_jumpers no)
		(fp_line
			(start 0.7874 0.4064)
			(end 0.7874 -0.4064)
			(stroke
				(width 0.1524)
				(type default)
			)
			(layer "B.SilkS")
		)
		(fp_line
			(start 0.7874 -0.4064)
			(end -0.7874 -0.4064)
			(stroke
				(width 0.1524)
				(type default)
			)
			(layer "B.SilkS")
		)
		(fp_line
			(start -0.7874 0.4064)
			(end 0.7874 0.4064)
			(stroke
				(width 0.1524)
				(type default)
			)
			(layer "B.SilkS")
		)
		(fp_line
			(start -0.7874 -0.4064)
			(end -0.7874 0.4064)
			(stroke
				(width 0.1524)
				(type default)
			)
			(layer "B.SilkS")
		)
		(fp_line
			(start 0.67945 0.3048)
			(end 0.67945 -0.305054)
			(stroke
				(width 0.1)
				(type default)
			)
			(layer "B.Fab")
		)
		(fp_line
			(start 0.67945 -0.305054)
			(end 0.12065 -0.305054)
			(stroke
				(width 0.1)
				(type default)
			)
			(layer "B.Fab")
		)
		(fp_line
			(start 0.12065 0.3048)
			(end 0.67945 0.3048)
			(stroke
				(width 0.1)
				(type default)
			)
			(layer "B.Fab")
		)
		(fp_line
			(start 0.12065 0.2794)
			(end 0.12065 0.3048)
			(stroke
				(width 0.1)
				(type default)
			)
			(layer "B.Fab")
		)
		(fp_line
			(start 0.12065 -0.2794)
			(end -0.12065 -0.2794)
			(stroke
				(width 0.1)
				(type default)
			)
			(layer "B.Fab")
		)
		(fp_line
			(start 0.12065 -0.305054)
			(end 0.12065 -0.2794)
			(stroke
				(width 0.1)
				(type default)
			)
			(layer "B.Fab")
		)
		(fp_line
			(start -0.120396 0.3048)
			(end -0.120396 0.2794)
			(stroke
				(width 0.1)
				(type default)
			)
			(layer "B.Fab")
		)
		(fp_line
			(start -0.120396 0.2794)
			(end 0.12065 0.2794)
			(stroke
				(width 0.1)
				(type default)
			)
			(layer "B.Fab")
		)
		(fp_line
			(start -0.12065 -0.2794)
			(end -0.12065 -0.3048)
			(stroke
				(width 0.1)
				(type default)
			)
			(layer "B.Fab")
		)
		(fp_line
			(start -0.12065 -0.3048)
			(end -0.67945 -0.3048)
			(stroke
				(width 0.1)
				(type default)
			)
			(layer "B.Fab")
		)
		(fp_line
			(start -0.67945 0.3048)
			(end -0.120396 0.3048)
			(stroke
				(width 0.1)
				(type default)
			)
			(layer "B.Fab")
		)
		(fp_line
			(start -0.67945 -0.3048)
			(end -0.67945 0.3048)
			(stroke
				(width 0.1)
				(type default)
			)
			(layer "B.Fab")
		)
		(pad "1" smd circle
			(at 0.40005 0)
			(size 0 0)
			(layers "B.Cu" "B.Mask" "B.Paste")
			(net "PVDDIO_P1")
		)
		(pad "2" smd circle
			(at -0.40005 0)
			(size 0 0)
			(layers "B.Cu" "B.Mask" "B.Paste")
			(net "GND")
		)
	)
	(footprint ""
		(layer "B.Cu")
		(at 361.316016 -256.012188 -90)
		(property "Reference" "C2580"
			(at 0 0 90)
			(layer "B.SilkS")
			(hide yes)
			(effects
				(font
					(size 1.27 1.27)
				)
				(justify mirror)
			)
		)
		(property "Value" ""
			(at 0 0 90)
			(layer "B.Fab")
			(effects
				(font
					(size 1.27 1.27)
				)
				(justify mirror)
			)
		)
		(duplicate_pad_numbers_are_jumpers no)
		(fp_line
			(start -0.7874 0.4064)
			(end 0.7874 0.4064)
			(stroke
				(width 0.1524)
				(type default)
			)
			(layer "B.SilkS")
		)
		(fp_line
			(start 0.7874 0.4064)
			(end 0.7874 -0.4064)
			(stroke
				(width 0.1524)
				(type default)
			)
			(layer "B.SilkS")
		)
		(fp_line
			(start -0.7874 -0.4064)
			(end -0.7874 0.4064)
			(stroke
				(width 0.1524)
				(type default)
			)
			(layer "B.SilkS")
		)
		(fp_line
			(start 0.7874 -0.4064)
			(end -0.7874 -0.4064)
			(stroke
				(width 0.1524)
				(type default)
			)
			(layer "B.SilkS")
		)
		(fp_line
			(start -0.67945 0.3048)
			(end -0.120396 0.3048)
			(stroke
				(width 0.1)
				(type default)
			)
			(layer "B.Fab")
		)
		(fp_line
			(start -0.120396 0.3048)
			(end -0.120396 0.2794)
			(stroke
				(width 0.1)
				(type default)
			)
			(layer "B.Fab")
		)
		(fp_line
			(start 0.12065 0.3048)
			(end 0.67945 0.3048)
			(stroke
				(width 0.1)
				(type default)
			)
			(layer "B.Fab")
		)
		(fp_line
			(start 0.67945 0.3048)
			(end 0.67945 -0.305054)
			(stroke
				(width 0.1)
				(type default)
			)
			(layer "B.Fab")
		)
		(fp_line
			(start -0.120396 0.2794)
			(end 0.12065 0.2794)
			(stroke
				(width 0.1)
				(type default)
			)
			(layer "B.Fab")
		)
		(fp_line
			(start 0.12065 0.2794)
			(end 0.12065 0.3048)
			(stroke
				(width 0.1)
				(type default)
			)
			(layer "B.Fab")
		)
		(fp_line
			(start -0.12065 -0.2794)
			(end -0.12065 -0.3048)
			(stroke
				(width 0.1)
				(type default)
			)
			(layer "B.Fab")
		)
		(fp_line
			(start 0.12065 -0.2794)
			(end -0.12065 -0.2794)
			(stroke
				(width 0.1)
				(type default)
			)
			(layer "B.Fab")
		)
		(fp_line
			(start -0.67945 -0.3048)
			(end -0.67945 0.3048)
			(stroke
				(width 0.1)
				(type default)
			)
			(layer "B.Fab")
		)
		(fp_line
			(start -0.12065 -0.3048)
			(end -0.67945 -0.3048)
			(stroke
				(width 0.1)
				(type default)
			)
			(layer "B.Fab")
		)
		(fp_line
			(start 0.12065 -0.305054)
			(end 0.12065 -0.2794)
			(stroke
				(width 0.1)
				(type default)
			)
			(layer "B.Fab")
		)
		(fp_line
			(start 0.67945 -0.305054)
			(end 0.12065 -0.305054)
			(stroke
				(width 0.1)
				(type default)
			)
			(layer "B.Fab")
		)
		(pad "1" smd circle
			(at 0.40005 0 90)
			(size 0 0)
			(layers "B.Cu" "B.Mask" "B.Paste")
			(net "PVDDCR_SOC_P0")
		)
		(pad "2" smd circle
			(at -0.40005 0 90)
			(size 0 0)
			(layers "B.Cu" "B.Mask" "B.Paste")
			(net "GND")
		)
	)
)
